# TIMECARD (Time Appliance Project (Time Card)) — schematic netlist excerpt (pin names and nets, part order shuffled) for the footprints in the layout excerpt that follows; sources: Cadence DE-HDL packaged netlist, KiCad conversion of R4006-B0001-02_R01.brd

R211  RESISTOR  100OHM 1%  pkg SMC_0402R_H016  page 10 : \1\ = XP3R3V_FPGA ; \2\ = FPGA_M0
SP64  NULL  pkg DUMMY  page 34
L17  FERRITEBEAD  600OHM 25%  pkg SMC_0603R_H037  page 18 : \1\ = XP3R3V_FPGA ; \2\ = VDD3V3_SHT31A

(kicad_pcb
	(version 20260206)
	(generator "pcbnew")
	(generator_version "10.0")
	(general
		(thickness 1.6)
		(legacy_teardrops no)
	)
	(paper "A4")
	(title_block
		(title "timecard-production-celestica-r4006 — R4006-B0001-02_R01.brd")
		(comment 1 "Time Appliance Project (Time Card) / footprints 106-108 of 1113")
	)
	(layers
		(0 "F.Cu" signal "TOP")
		(4 "In1.Cu" signal "L02_GND1")
		(6 "In2.Cu" signal "L03_SIG1")
		(8 "In3.Cu" signal "L04_GND2")
		(10 "In4.Cu" signal "L05_VCC1")
		(12 "In5.Cu" signal "L06_VCC2")
		(14 "In6.Cu" signal "L07_GND3")
		(16 "In7.Cu" signal "L08_SIG2")
		(18 "In8.Cu" signal "L09_GND4")
		(2 "B.Cu" signal "BOTTOM")
		(9 "F.Adhes" user "F.Adhesive")
		(11 "B.Adhes" user "B.Adhesive")
		(13 "F.Paste" user "Package Geometry/Pastemask Top")
		(15 "B.Paste" user "Package Geometry/Pastemask Bottom")
		(5 "F.SilkS" user "Ref Des/Silkscreen Top")
		(7 "B.SilkS" user "Ref Des/Silkscreen Bottom")
		(1 "F.Mask" user "Board Geometry/Soldermask Top")
		(3 "B.Mask" user "Board Geometry/Soldermask Bottom")
		(17 "Dwgs.User" user "User.Drawings")
		(19 "Cmts.User" user "User.Comments")
		(21 "Eco1.User" user "User.Eco1")
		(23 "Eco2.User" user "User.Eco2")
		(25 "Edge.Cuts" user "Board Geometry/Outline")
		(27 "Margin" user)
		(31 "F.CrtYd" user "Package Geometry/Place Bound Top")
		(29 "B.CrtYd" user "Package Geometry/Place Bound Bottom")
		(35 "F.Fab" user "Ref Des/Assembly Top")
		(33 "B.Fab" user "Ref Des/Assembly Bottom")
	)
	(footprint ""
		(layer "F.Cu")
		(at 153.924 -59.0296 180)
		(property "Reference" "L17"
			(at 0 1.51003 0)
			(unlocked yes)
			(layer "F.SilkS")
			(effects
				(font
					(size 0.7874 0.5842)
					(thickness 0.1524)
				)
			)
		)
		(property "Value" "VAL*"
			(at 0.014732 2.526538 180)
			(unlocked yes)
			(layer "F.Fab")
			(hide yes)
			(effects
				(font
					(size 0.7874 0.5842)
					(thickness 0.000001)
				)
			)
		)
		(property "Tolerance" "TOL*"
			(at 0.014732 3.503676 180)
			(unlocked yes)
			(layer "Cmts.User")
			(hide yes)
			(effects
				(font
					(size 0.7874 0.5842)
					(thickness 0.000001)
				)
			)
		)
		(property "User Part Number" "PARTNUM*"
			(at 0.02794 4.480814 180)
			(unlocked yes)
			(layer "Cmts.User")
			(hide yes)
			(effects
				(font
					(size 0.7874 0.5842)
					(thickness 0.000001)
				)
			)
		)
		(property "Device Type" "FERRITEBEAD-G191-10097-01,600OA"
			(at 0.014732 1.600708 180)
			(unlocked yes)
			(layer "F.Fab")
			(hide yes)
			(effects
				(font
					(size 0.7874 0.5842)
					(thickness 0.000001)
				)
			)
		)
		(duplicate_pad_numbers_are_jumpers no)
		(fp_line
			(start 1.3208 0.7112)
			(end -1.3208 0.7112)
			(stroke
				(width 0.1)
				(type default)
			)
			(layer "F.SilkS")
		)
		(fp_line
			(start 1.3208 -0.7112)
			(end 1.3208 0.7112)
			(stroke
				(width 0.1)
				(type default)
			)
			(layer "F.SilkS")
		)
		(fp_line
			(start -1.3208 0.7112)
			(end -1.3208 -0.7112)
			(stroke
				(width 0.1)
				(type default)
			)
			(layer "F.SilkS")
		)
		(fp_line
			(start -1.3208 -0.7112)
			(end 1.3208 -0.7112)
			(stroke
				(width 0.1)
				(type default)
			)
			(layer "F.SilkS")
		)
		(fp_rect
			(start -1.3208 0.7112)
			(end 1.3208 -0.7112)
			(stroke
				(width 0)
				(type default)
			)
			(fill no)
			(layer "F.CrtYd")
		)
		(fp_line
			(start 0.8128 0.4572)
			(end -0.8128 0.4572)
			(stroke
				(width 0.1)
				(type default)
			)
			(layer "F.Fab")
		)
		(fp_line
			(start 0.8128 -0.4572)
			(end 0.8128 0.4572)
			(stroke
				(width 0.1)
				(type default)
			)
			(layer "F.Fab")
		)
		(fp_line
			(start -0.8128 0.4572)
			(end -0.8128 -0.4572)
			(stroke
				(width 0.1)
				(type default)
			)
			(layer "F.Fab")
		)
		(fp_line
			(start -0.8128 -0.4572)
			(end 0.8128 -0.4572)
			(stroke
				(width 0.1)
				(type default)
			)
			(layer "F.Fab")
		)
		(pad "1" smd rect
			(at -0.6858 0 180)
			(size 0.762 0.8636)
			(layers "F.Cu" "F.Mask" "F.Paste")
			(net "XP3R3V_FPGA")
		)
		(pad "2" smd rect
			(at 0.6858 0 180)
			(size 0.762 0.8636)
			(layers "F.Cu" "F.Mask" "F.Paste")
			(net "VDD3V3_SHT31A")
		)
		(zone
			(layer "F.Cu")
			(hatch none 0.5)
			(connect_pads
				(clearance 0)
			)
			(min_thickness 0.25)
			(keepout
				(tracks allowed)
				(vias not_allowed)
				(pads allowed)
				(copperpour not_allowed)
				(footprints allowed)
			)
			(placement
				(enabled no)
				(sheetname "")
			)
			(fill
				(thermal_gap 0.5)
				(thermal_bridge_width 0.5)
				(island_removal_mode 0)
			)
			(polygon
				(pts
					(xy 154.0764 -59.4868) (xy 153.7716 -59.4868) (xy 153.7716 -58.5724) (xy 154.0764 -58.5724)
				)
			)
		)
		(zone
			(layer "F.Cu")
			(hatch none 0.5)
			(connect_pads
				(clearance 0)
			)
			(min_thickness 0.25)
			(keepout
				(tracks not_allowed)
				(vias allowed)
				(pads allowed)
				(copperpour not_allowed)
				(footprints allowed)
			)
			(placement
				(enabled no)
				(sheetname "")
			)
			(fill
				(thermal_gap 0.5)
				(thermal_bridge_width 0.5)
				(island_removal_mode 0)
			)
			(polygon
				(pts
					(xy 154.0764 -59.4868) (xy 153.7716 -59.4868) (xy 153.7716 -58.5724) (xy 154.0764 -58.5724)
				)
			)
		)
	)
	(footprint ""
		(layer "F.Cu")
		(at 124.587 -44.831 180)
		(property "Reference" "R211"
			(at -3.048 1.35763 0)
			(unlocked yes)
			(layer "F.SilkS")
			(effects
				(font
					(size 0.7874 0.5842)
					(thickness 0.1524)
				)
			)
		)
		(property "Value" "VAL*"
			(at 0.02032 2.13233 180)
			(unlocked yes)
			(layer "F.Fab")
			(hide yes)
			(effects
				(font
					(size 0.7874 0.5842)
					(thickness 0.1524)
				)
			)
		)
		(property "Device Type" "RESISTOR-G155-11000-01,100OHM,A"
			(at 0.008382 1.210564 180)
			(unlocked yes)
			(layer "F.Fab")
			(hide yes)
			(effects
				(font
					(size 0.7874 0.5842)
					(thickness 0.1524)
				)
			)
		)
		(property "User Part Number" "PARTNUM*"
			(at 0.02032 4.024884 180)
			(unlocked yes)
			(layer "Cmts.User")
			(hide yes)
			(effects
				(font
					(size 0.7874 0.5842)
					(thickness 0.1524)
				)
			)
		)
		(property "Tolerance" "TOL*"
			(at 0.044704 3.05435 180)
			(unlocked yes)
			(layer "Cmts.User")
			(hide yes)
			(effects
				(font
					(size 0.7874 0.5842)
					(thickness 0.1524)
				)
			)
		)
		(duplicate_pad_numbers_are_jumpers no)
		(fp_line
			(start 1.143 0.5588)
			(end 1.143 -0.5588)
			(stroke
				(width 0.1)
				(type default)
			)
			(layer "F.SilkS")
		)
		(fp_line
			(start 1.143 -0.5588)
			(end -1.143 -0.5588)
			(stroke
				(width 0.1)
				(type default)
			)
			(layer "F.SilkS")
		)
		(fp_line
			(start -1.143 0.5588)
			(end 1.143 0.5588)
			(stroke
				(width 0.1)
				(type default)
			)
			(layer "F.SilkS")
		)
		(fp_line
			(start -1.143 -0.5588)
			(end -1.143 0.5588)
			(stroke
				(width 0.1)
				(type default)
			)
			(layer "F.SilkS")
		)
		(fp_rect
			(start 1.143 0.5588)
			(end -1.143 -0.5588)
			(stroke
				(width 0)
				(type default)
			)
			(fill no)
			(layer "F.CrtYd")
		)
		(fp_line
			(start 0.508 0.3048)
			(end 0.508 -0.3048)
			(stroke
				(width 0.1)
				(type default)
			)
			(layer "F.Fab")
		)
		(fp_line
			(start 0.508 -0.3048)
			(end -0.508 -0.3048)
			(stroke
				(width 0.1)
				(type default)
			)
			(layer "F.Fab")
		)
		(fp_line
			(start -0.508 0.3048)
			(end 0.508 0.3048)
			(stroke
				(width 0.1)
				(type default)
			)
			(layer "F.Fab")
		)
		(fp_line
			(start -0.508 -0.3048)
			(end -0.508 0.3048)
			(stroke
				(width 0.1)
				(type default)
			)
			(layer "F.Fab")
		)
		(pad "1" smd rect
			(at -0.5334 0 180)
			(size 0.7112 0.6096)
			(layers "F.Cu" "F.Mask" "F.Paste")
			(net "XP3R3V_FPGA")
		)
		(pad "2" smd rect
			(at 0.5334 0 180)
			(size 0.7112 0.6096)
			(layers "F.Cu" "F.Mask" "F.Paste")
			(net "FPGA_M0")
		)
		(zone
			(layer "F.Cu")
			(hatch none 0.5)
			(connect_pads
				(clearance 0)
			)
			(min_thickness 0.25)
			(keepout
				(tracks allowed)
				(vias not_allowed)
				(pads allowed)
				(copperpour not_allowed)
				(footprints allowed)
			)
			(placement
				(enabled no)
				(sheetname "")
			)
			(fill
				(thermal_gap 0.5)
				(thermal_bridge_width 0.5)
				(island_removal_mode 0)
			)
			(polygon
				(pts
					(xy 124.5108 -45.1358) (xy 124.5108 -44.5262) (xy 124.6632 -44.5262) (xy 124.6632 -45.1358)
				)
			)
		)
	)
	(footprint ""
		(layer "F.Cu")
		(at 44.069 -130.429)
		(property "Reference" "SP64"
			(at 0 0 0)
			(layer "F.SilkS")
			(hide yes)
			(effects
				(font
					(size 1.27 1.27)
				)
			)
		)
		(property "Value" ""
			(at 0 0 0)
			(layer "F.Fab")
			(effects
				(font
					(size 1.27 1.27)
				)
			)
		)
		(duplicate_pad_numbers_are_jumpers no)
	)
)
